(kicad_pcb
	(version 20260206)
	(generator "pcbnew")
	(generator_version "10.0")
	(general
		(thickness 1.6)
		(legacy_teardrops no)
	)
	(paper "A4")
	(title_block
		(title "04192023_DAF0TMB3IC0_F0TG_MB_C_brd_V02_OCP.brd")
		(comment 1 "Grand Teton / footprint 3102 of 8354 (U6011), pads 1-111 of 354")
	)
	(layers
		(0 "F.Cu" signal "TOP")
		(4 "In1.Cu" signal "GND")
		(6 "In2.Cu" signal "IN1")
		(8 "In3.Cu" signal "GND1")
		(10 "In4.Cu" signal "IN2")
		(12 "In5.Cu" signal "GND2")
		(14 "In6.Cu" signal "IN3")
		(16 "In7.Cu" signal "GND3")
		(18 "In8.Cu" signal "VCC")
		(20 "In9.Cu" signal "VCC1")
		(22 "In10.Cu" signal "GND4")
		(24 "In11.Cu" signal "IN4")
		(26 "In12.Cu" signal "GND5")
		(28 "In13.Cu" signal "IN5")
		(30 "In14.Cu" signal "GND6")
		(32 "In15.Cu" signal "IN6")
		(34 "In16.Cu" signal "GND7")
		(2 "B.Cu" signal "BOTTOM")
		(9 "F.Adhes" user "F.Adhesive")
		(11 "B.Adhes" user "B.Adhesive")
		(13 "F.Paste" user "Package Geometry/Pastemask Top")
		(15 "B.Paste" user "Package Geometry/Pastemask Bottom")
		(5 "F.SilkS" user "Ref Des/Silkscreen Top")
		(7 "B.SilkS" user "Ref Des/Silkscreen Bottom")
		(1 "F.Mask" user "Board Geometry/Soldermask Top")
		(3 "B.Mask" user "Board Geometry/Soldermask Bottom")
		(17 "Dwgs.User" user "User.Drawings")
		(19 "Cmts.User" user "User.Comments")
		(21 "Eco1.User" user "User.Eco1")
		(23 "Eco2.User" user "User.Eco2")
		(25 "Edge.Cuts" user "Board Geometry/Outline")
		(27 "Margin" user)
		(31 "F.CrtYd" user "Package Geometry/Place Bound Top")
		(29 "B.CrtYd" user "Package Geometry/Place Bound Bottom")
		(35 "F.Fab" user "Ref Des/Assembly Top")
		(33 "B.Fab" user "Ref Des/Assembly Bottom")
	)
	(footprint ""
		(layer "F.Cu")
		(at 344.9955 -395.724634)
		(property "Reference" "U6011"
			(at -8.11784 -7.526528 0)
			(unlocked yes)
			(layer "F.SilkS")
			(effects
				(font
					(size 0.7874 0.5842)
					(thickness 0.1524)
				)
				(justify left)
			)
		)
		(property "Value" ""
			(at 0 0 0)
			(layer "F.Fab")
			(effects
				(font
					(size 1.27 1.27)
				)
			)
		)
		(duplicate_pad_numbers_are_jumpers no)
		(pad "A1" smd oval
			(at 11.050016 -3.938524)
			(size 0.254 0.3302)
			(layers "F.Cu" "F.Mask" "F.Paste")
			(net "NCF_A1_CPU0_P1_GND")
		)
		(pad "A35" smd oval
			(at 11.050016 3.940048)
			(size 0.254 0.3302)
			(layers "F.Cu" "F.Mask" "F.Paste")
			(net "NCF_CPU0_P1_GND")
		)
		(pad "AA10" smd circle
			(at 7.602728 -1.431798)
			(size 0.381 0.381)
			(layers "F.Cu" "F.Mask" "F.Paste")
			(net "P5E_CPU0_P1_TX_BUF_DN<14>")
		)
		(pad "AA29" smd circle
			(at 7.602728 2.032254)
			(size 0.381 0.381)
			(layers "F.Cu" "F.Mask" "F.Paste")
			(net "P5E_CPU0_P1_RX_DN<14>")
		)
		(pad "AB1" smd oval
			(at 7.450074 -3.938524)
			(size 0.254 0.3302)
			(layers "F.Cu" "F.Mask" "F.Paste")
			(net "P5E_CPU0_P1_RX_BUF_DP<14>")
		)
		(pad "AB35" smd oval
			(at 7.450074 3.940048)
			(size 0.254 0.3302)
			(layers "F.Cu" "F.Mask" "F.Paste")
			(net "P5E_CPU0_P1_TX_C_DN<14>")
		)
		(pad "AC4" smd circle
			(at 7.202678 -2.817368)
			(size 0.381 0.381)
			(layers "F.Cu" "F.Mask" "F.Paste")
			(net "GND")
		)
		(pad "AC13" smd circle
			(at 7.202678 -0.79629)
			(size 0.3048 0.3048)
			(layers "F.Cu" "F.Mask" "F.Paste")
			(net "GND")
		)
		(pad "AC17" smd circle
			(at 7.202678 -0.296164)
			(size 0.3048 0.3048)
			(layers "F.Cu" "F.Mask" "F.Paste")
			(net "P0V9_CPU0_RT1_2A")
		)
		(pad "AC20" smd circle
			(at 7.202678 0.203708)
			(size 0.3048 0.3048)
			(layers "F.Cu" "F.Mask" "F.Paste")
			(net "P0V9_CPU0_RT1_2A")
		)
		(pad "AC22" smd circle
			(at 7.202678 0.703834)
			(size 0.3048 0.3048)
			(layers "F.Cu" "F.Mask" "F.Paste")
			(net "GND")
		)
		(pad "AC32" smd circle
			(at 7.202678 2.724912)
			(size 0.381 0.381)
			(layers "F.Cu" "F.Mask" "F.Paste")
			(net "GND")
		)
		(pad "AD2" smd circle
			(at 7.1501 -3.41884)
			(size 0.3048 0.3048)
			(layers "F.Cu" "F.Mask" "F.Paste")
			(net "GND")
		)
		(pad "AD34" smd circle
			(at 7.1501 3.420364)
			(size 0.3048 0.3048)
			(layers "F.Cu" "F.Mask" "F.Paste")
			(net "GND")
		)
		(pad "AE1" smd oval
			(at 6.849872 -3.938524)
			(size 0.254 0.3302)
			(layers "F.Cu" "F.Mask" "F.Paste")
			(net "GND")
		)
		(pad "AE35" smd oval
			(at 6.849872 3.940048)
			(size 0.254 0.3302)
			(layers "F.Cu" "F.Mask" "F.Paste")
			(net "GND")
		)
		(pad "AF7" smd circle
			(at 6.802628 -2.12471)
			(size 0.381 0.381)
			(layers "F.Cu" "F.Mask" "F.Paste")
			(net "P5E_CPU0_P1_TX_BUF_DP<13>")
		)
		(pad "AF26" smd circle
			(at 6.802628 1.339342)
			(size 0.381 0.381)
			(layers "F.Cu" "F.Mask" "F.Paste")
			(net "P5E_CPU0_P1_RX_DP<13>")
		)
		(pad "AG2" smd circle
			(at 6.549898 -3.41884)
			(size 0.3048 0.3048)
			(layers "F.Cu" "F.Mask" "F.Paste")
			(net "P5E_CPU0_P1_RX_BUF_DN<13>")
		)
		(pad "AG34" smd circle
			(at 6.549898 3.420364)
			(size 0.3048 0.3048)
			(layers "F.Cu" "F.Mask" "F.Paste")
			(net "P5E_CPU0_P1_TX_C_DN<13>")
		)
		(pad "AH10" smd circle
			(at 6.402578 -1.431798)
			(size 0.381 0.381)
			(layers "F.Cu" "F.Mask" "F.Paste")
			(net "P5E_CPU0_P1_TX_BUF_DN<13>")
		)
		(pad "AH29" smd circle
			(at 6.402578 2.032254)
			(size 0.381 0.381)
			(layers "F.Cu" "F.Mask" "F.Paste")
			(net "P5E_CPU0_P1_RX_DN<13>")
		)
		(pad "AJ1" smd oval
			(at 6.249924 -3.938524)
			(size 0.254 0.3302)
			(layers "F.Cu" "F.Mask" "F.Paste")
			(net "P5E_CPU0_P1_RX_BUF_DP<13>")
		)
		(pad "AJ35" smd oval
			(at 6.249924 3.940048)
			(size 0.254 0.3302)
			(layers "F.Cu" "F.Mask" "F.Paste")
			(net "P5E_CPU0_P1_TX_C_DP<13>")
		)
		(pad "AK4" smd circle
			(at 6.002528 -2.817368)
			(size 0.381 0.381)
			(layers "F.Cu" "F.Mask" "F.Paste")
			(net "GND")
		)
		(pad "AK13" smd circle
			(at 6.002528 -0.79629)
			(size 0.3048 0.3048)
			(layers "F.Cu" "F.Mask" "F.Paste")
			(net "GND")
		)
		(pad "AK17" smd circle
			(at 6.002528 -0.296164)
			(size 0.3048 0.3048)
			(layers "F.Cu" "F.Mask" "F.Paste")
			(net "P0V9_CPU0_RT1_2A")
		)
		(pad "AK20" smd circle
			(at 6.002528 0.203708)
			(size 0.3048 0.3048)
			(layers "F.Cu" "F.Mask" "F.Paste")
			(net "P0V9_CPU0_RT1_2A")
		)
		(pad "AK22" smd circle
			(at 6.002528 0.703834)
			(size 0.3048 0.3048)
			(layers "F.Cu" "F.Mask" "F.Paste")
			(net "GND")
		)
		(pad "AK32" smd circle
			(at 6.002528 2.724912)
			(size 0.381 0.381)
			(layers "F.Cu" "F.Mask" "F.Paste")
			(net "GND")
		)
		(pad "AL2" smd circle
			(at 5.94995 -3.41884)
			(size 0.3048 0.3048)
			(layers "F.Cu" "F.Mask" "F.Paste")
			(net "GND")
		)
		(pad "AL34" smd circle
			(at 5.94995 3.420364)
			(size 0.3048 0.3048)
			(layers "F.Cu" "F.Mask" "F.Paste")
			(net "GND")
		)
		(pad "AM1" smd oval
			(at 5.649976 -3.938524)
			(size 0.254 0.3302)
			(layers "F.Cu" "F.Mask" "F.Paste")
			(net "GND")
		)
		(pad "AM35" smd oval
			(at 5.649976 3.940048)
			(size 0.254 0.3302)
			(layers "F.Cu" "F.Mask" "F.Paste")
			(net "GND")
		)
		(pad "AN7" smd circle
			(at 5.602478 -2.12471)
			(size 0.381 0.381)
			(layers "F.Cu" "F.Mask" "F.Paste")
			(net "P5E_CPU0_P1_TX_BUF_DP<12>")
		)
		(pad "AN26" smd circle
			(at 5.602478 1.339342)
			(size 0.381 0.381)
			(layers "F.Cu" "F.Mask" "F.Paste")
			(net "P5E_CPU0_P1_RX_DP<12>")
		)
		(pad "AP2" smd circle
			(at 5.350002 -3.41884)
			(size 0.3048 0.3048)
			(layers "F.Cu" "F.Mask" "F.Paste")
			(net "P5E_CPU0_P1_RX_BUF_DN<12>")
		)
		(pad "AP34" smd circle
			(at 5.350002 3.420364)
			(size 0.3048 0.3048)
			(layers "F.Cu" "F.Mask" "F.Paste")
			(net "P5E_CPU0_P1_TX_C_DN<12>")
		)
		(pad "AR10" smd circle
			(at 5.202682 -1.431798)
			(size 0.381 0.381)
			(layers "F.Cu" "F.Mask" "F.Paste")
			(net "P5E_CPU0_P1_TX_BUF_DN<12>")
		)
		(pad "AR29" smd circle
			(at 5.202682 2.032254)
			(size 0.381 0.381)
			(layers "F.Cu" "F.Mask" "F.Paste")
			(net "P5E_CPU0_P1_RX_DN<12>")
		)
		(pad "AT1" smd oval
			(at 5.050028 -3.938524)
			(size 0.254 0.3302)
			(layers "F.Cu" "F.Mask" "F.Paste")
			(net "P5E_CPU0_P1_RX_BUF_DP<12>")
		)
		(pad "AT35" smd oval
			(at 5.050028 3.940048)
			(size 0.254 0.3302)
			(layers "F.Cu" "F.Mask" "F.Paste")
			(net "P5E_CPU0_P1_TX_C_DP<12>")
		)
		(pad "AU4" smd circle
			(at 4.802632 -2.817368)
			(size 0.381 0.381)
			(layers "F.Cu" "F.Mask" "F.Paste")
			(net "GND")
		)
		(pad "AU13" smd circle
			(at 4.802632 -0.79629)
			(size 0.3048 0.3048)
			(layers "F.Cu" "F.Mask" "F.Paste")
			(net "GND")
		)
		(pad "AU17" smd circle
			(at 4.802632 -0.296164)
			(size 0.3048 0.3048)
			(layers "F.Cu" "F.Mask" "F.Paste")
			(net "P0V9_CPU0_RT1_2A")
		)
		(pad "AU20" smd circle
			(at 4.802632 0.203708)
			(size 0.3048 0.3048)
			(layers "F.Cu" "F.Mask" "F.Paste")
			(net "P0V9_CPU0_RT1_2A")
		)
		(pad "AU22" smd circle
			(at 4.802632 0.703834)
			(size 0.3048 0.3048)
			(layers "F.Cu" "F.Mask" "F.Paste")
			(net "GND")
		)
		(pad "AU32" smd circle
			(at 4.802632 2.724912)
			(size 0.381 0.381)
			(layers "F.Cu" "F.Mask" "F.Paste")
			(net "GND")
		)
		(pad "AV2" smd circle
			(at 4.750054 -3.41884)
			(size 0.3048 0.3048)
			(layers "F.Cu" "F.Mask" "F.Paste")
			(net "GND")
		)
		(pad "AV34" smd circle
			(at 4.750054 3.420364)
			(size 0.3048 0.3048)
			(layers "F.Cu" "F.Mask" "F.Paste")
			(net "GND")
		)
		(pad "AW1" smd oval
			(at 4.45008 -3.938524)
			(size 0.254 0.3302)
			(layers "F.Cu" "F.Mask" "F.Paste")
			(net "GND")
		)
		(pad "AW35" smd oval
			(at 4.45008 3.940048)
			(size 0.254 0.3302)
			(layers "F.Cu" "F.Mask" "F.Paste")
			(net "GND")
		)
		(pad "AY7" smd circle
			(at 4.402582 -2.12471)
			(size 0.381 0.381)
			(layers "F.Cu" "F.Mask" "F.Paste")
			(net "P5E_CPU0_P1_TX_BUF_DP<11>")
		)
		(pad "AY26" smd circle
			(at 4.402582 1.339342)
			(size 0.381 0.381)
			(layers "F.Cu" "F.Mask" "F.Paste")
			(net "P5E_CPU0_P1_RX_DP<11>")
		)
		(pad "B3" smd oval
			(at 10.885932 -2.888488 90)
			(size 0.254 0.3302)
			(layers "F.Cu" "F.Mask" "F.Paste")
			(net "JTAG_TCK_RT_CPU0_P1")
		)
		(pad "B6" smd oval
			(at 10.885932 -2.288286 90)
			(size 0.254 0.3302)
			(layers "F.Cu" "F.Mask" "F.Paste")
			(net "JTAG_TDI_RT_CPU0_P1")
		)
		(pad "B9" smd oval
			(at 10.885932 -1.688338 90)
			(size 0.254 0.3302)
			(layers "F.Cu" "F.Mask" "F.Paste")
			(net "JTAG_TDO_RT_CPU0_P1")
		)
		(pad "B12" smd oval
			(at 10.885932 -1.08839 90)
			(size 0.254 0.3302)
			(layers "F.Cu" "F.Mask" "F.Paste")
			(net "JTAG_TMS_RT_CPU0_P1")
		)
		(pad "B16" smd oval
			(at 10.885932 -0.488442 90)
			(size 0.254 0.3302)
			(layers "F.Cu" "F.Mask" "F.Paste")
			(net "Net_2207")
		)
		(pad "B19" smd oval
			(at 10.885932 0.111506 90)
			(size 0.254 0.3302)
			(layers "F.Cu" "F.Mask" "F.Paste")
			(net "GND")
		)
		(pad "B23" smd oval
			(at 10.885932 0.711708 90)
			(size 0.254 0.3302)
			(layers "F.Cu" "F.Mask" "F.Paste")
			(net "RT_CPU0_P1_ADDR2")
		)
		(pad "B25" smd oval
			(at 10.885932 1.311656 90)
			(size 0.254 0.3302)
			(layers "F.Cu" "F.Mask" "F.Paste")
			(net "RT_CPU0_P1_ADDR3")
		)
		(pad "B28" smd oval
			(at 10.885932 1.911604 90)
			(size 0.254 0.3302)
			(layers "F.Cu" "F.Mask" "F.Paste")
			(net "SMB_RT_CPU0_P1_R2_SDA")
		)
		(pad "B31" smd oval
			(at 10.885932 2.511552 90)
			(size 0.254 0.3302)
			(layers "F.Cu" "F.Mask" "F.Paste")
			(net "SMB_RT_CPU0_P1_R2_SCL")
		)
		(pad "BA2" smd circle
			(at 4.150106 -3.41884)
			(size 0.3048 0.3048)
			(layers "F.Cu" "F.Mask" "F.Paste")
			(net "P5E_CPU0_P1_RX_BUF_DN<11>")
		)
		(pad "BA34" smd circle
			(at 4.150106 3.420364)
			(size 0.3048 0.3048)
			(layers "F.Cu" "F.Mask" "F.Paste")
			(net "P5E_CPU0_P1_TX_C_DN<11>")
		)
		(pad "BB10" smd circle
			(at 4.002532 -1.431798)
			(size 0.381 0.381)
			(layers "F.Cu" "F.Mask" "F.Paste")
			(net "P5E_CPU0_P1_TX_BUF_DN<11>")
		)
		(pad "BB29" smd circle
			(at 4.002532 2.032254)
			(size 0.381 0.381)
			(layers "F.Cu" "F.Mask" "F.Paste")
			(net "P5E_CPU0_P1_RX_DN<11>")
		)
		(pad "BC1" smd oval
			(at 3.849878 -3.938524)
			(size 0.254 0.3302)
			(layers "F.Cu" "F.Mask" "F.Paste")
			(net "P5E_CPU0_P1_RX_BUF_DP<11>")
		)
		(pad "BC35" smd oval
			(at 3.849878 3.940048)
			(size 0.254 0.3302)
			(layers "F.Cu" "F.Mask" "F.Paste")
			(net "P5E_CPU0_P1_TX_C_DP<11>")
		)
		(pad "BD4" smd circle
			(at 3.602482 -2.817368)
			(size 0.381 0.381)
			(layers "F.Cu" "F.Mask" "F.Paste")
			(net "GND")
		)
		(pad "BD13" smd circle
			(at 3.602482 -0.79629)
			(size 0.3048 0.3048)
			(layers "F.Cu" "F.Mask" "F.Paste")
			(net "GND")
		)
		(pad "BD17" smd circle
			(at 3.602482 -0.296164)
			(size 0.3048 0.3048)
			(layers "F.Cu" "F.Mask" "F.Paste")
			(net "P0V9_CPU0_RT1_2A_2D")
		)
		(pad "BD20" smd circle
			(at 3.602482 0.203708)
			(size 0.3048 0.3048)
			(layers "F.Cu" "F.Mask" "F.Paste")
			(net "P0V9_CPU0_RT1_2A_2D")
		)
		(pad "BD22" smd circle
			(at 3.602482 0.703834)
			(size 0.3048 0.3048)
			(layers "F.Cu" "F.Mask" "F.Paste")
			(net "GND")
		)
		(pad "BD32" smd circle
			(at 3.602482 2.724912)
			(size 0.381 0.381)
			(layers "F.Cu" "F.Mask" "F.Paste")
			(net "GND")
		)
		(pad "BE2" smd circle
			(at 3.549904 -3.41884)
			(size 0.3048 0.3048)
			(layers "F.Cu" "F.Mask" "F.Paste")
			(net "GND")
		)
		(pad "BE34" smd circle
			(at 3.549904 3.420364)
			(size 0.3048 0.3048)
			(layers "F.Cu" "F.Mask" "F.Paste")
			(net "GND")
		)
		(pad "BF1" smd oval
			(at 3.24993 -3.938524)
			(size 0.254 0.3302)
			(layers "F.Cu" "F.Mask" "F.Paste")
			(net "GND")
		)
		(pad "BF35" smd oval
			(at 3.24993 3.940048)
			(size 0.254 0.3302)
			(layers "F.Cu" "F.Mask" "F.Paste")
			(net "GND")
		)
		(pad "BG7" smd circle
			(at 3.202686 -2.12471)
			(size 0.381 0.381)
			(layers "F.Cu" "F.Mask" "F.Paste")
			(net "P5E_CPU0_P1_TX_BUF_DP<10>")
		)
		(pad "BG26" smd circle
			(at 3.202686 1.339342)
			(size 0.381 0.381)
			(layers "F.Cu" "F.Mask" "F.Paste")
			(net "P5E_CPU0_P1_RX_DP<10>")
		)
		(pad "BH2" smd circle
			(at 2.949956 -3.41884)
			(size 0.3048 0.3048)
			(layers "F.Cu" "F.Mask" "F.Paste")
			(net "P5E_CPU0_P1_RX_BUF_DN<10>")
		)
		(pad "BH34" smd circle
			(at 2.949956 3.420364)
			(size 0.3048 0.3048)
			(layers "F.Cu" "F.Mask" "F.Paste")
			(net "P5E_CPU0_P1_TX_C_DN<10>")
		)
		(pad "BJ10" smd circle
			(at 2.802636 -1.431798)
			(size 0.381 0.381)
			(layers "F.Cu" "F.Mask" "F.Paste")
			(net "P5E_CPU0_P1_TX_BUF_DN<10>")
		)
		(pad "BJ29" smd circle
			(at 2.802636 2.032254)
			(size 0.381 0.381)
			(layers "F.Cu" "F.Mask" "F.Paste")
			(net "P5E_CPU0_P1_RX_DN<10>")
		)
		(pad "BK1" smd oval
			(at 2.649982 -3.938524)
			(size 0.254 0.3302)
			(layers "F.Cu" "F.Mask" "F.Paste")
			(net "P5E_CPU0_P1_RX_BUF_DP<10>")
		)
		(pad "BK35" smd oval
			(at 2.649982 3.940048)
			(size 0.254 0.3302)
			(layers "F.Cu" "F.Mask" "F.Paste")
			(net "P5E_CPU0_P1_TX_C_DP<10>")
		)
		(pad "BL4" smd circle
			(at 2.402586 -2.817368)
			(size 0.381 0.381)
			(layers "F.Cu" "F.Mask" "F.Paste")
			(net "GND")
		)
		(pad "BL13" smd circle
			(at 2.402586 -0.79629)
			(size 0.3048 0.3048)
			(layers "F.Cu" "F.Mask" "F.Paste")
			(net "GND")
		)
		(pad "BL17" smd circle
			(at 2.402586 -0.296164)
			(size 0.3048 0.3048)
			(layers "F.Cu" "F.Mask" "F.Paste")
			(net "P0V9_CPU0_RT_2D")
		)
		(pad "BL20" smd circle
			(at 2.402586 0.203708)
			(size 0.3048 0.3048)
			(layers "F.Cu" "F.Mask" "F.Paste")
			(net "P0V9_CPU0_RT_2D")
		)
		(pad "BL22" smd circle
			(at 2.402586 0.703834)
			(size 0.3048 0.3048)
			(layers "F.Cu" "F.Mask" "F.Paste")
			(net "GND")
		)
		(pad "BL32" smd circle
			(at 2.402586 2.724912)
			(size 0.381 0.381)
			(layers "F.Cu" "F.Mask" "F.Paste")
			(net "GND")
		)
		(pad "BM2" smd circle
			(at 2.350008 -3.41884)
			(size 0.3048 0.3048)
			(layers "F.Cu" "F.Mask" "F.Paste")
			(net "GND")
		)
		(pad "BM34" smd circle
			(at 2.350008 3.420364)
			(size 0.3048 0.3048)
			(layers "F.Cu" "F.Mask" "F.Paste")
			(net "GND")
		)
		(pad "BN1" smd oval
			(at 2.050034 -3.938524)
			(size 0.254 0.3302)
			(layers "F.Cu" "F.Mask" "F.Paste")
			(net "GND")
		)
		(pad "BN35" smd oval
			(at 2.050034 3.940048)
			(size 0.254 0.3302)
			(layers "F.Cu" "F.Mask" "F.Paste")
			(net "GND")
		)
		(pad "BP7" smd circle
			(at 2.002536 -2.12471)
			(size 0.381 0.381)
			(layers "F.Cu" "F.Mask" "F.Paste")
			(net "P5E_CPU0_P1_TX_BUF_DP<9>")
		)
		(pad "BP26" smd circle
			(at 2.002536 1.339342)
			(size 0.381 0.381)
			(layers "F.Cu" "F.Mask" "F.Paste")
			(net "P5E_CPU0_P1_RX_DP<9>")
		)
		(pad "BR2" smd circle
			(at 1.75006 -3.41884)
			(size 0.3048 0.3048)
			(layers "F.Cu" "F.Mask" "F.Paste")
			(net "P5E_CPU0_P1_RX_BUF_DN<9>")
		)
		(pad "BR34" smd circle
			(at 1.75006 3.420364)
			(size 0.3048 0.3048)
			(layers "F.Cu" "F.Mask" "F.Paste")
			(net "P5E_CPU0_P1_TX_C_DN<9>")
		)
		(pad "BT10" smd circle
			(at 1.602486 -1.431798)
			(size 0.381 0.381)
			(layers "F.Cu" "F.Mask" "F.Paste")
			(net "P5E_CPU0_P1_TX_BUF_DN<9>")
		)
		(pad "BT29" smd circle
			(at 1.602486 2.032254)
			(size 0.381 0.381)
			(layers "F.Cu" "F.Mask" "F.Paste")
			(net "P5E_CPU0_P1_RX_DN<9>")
		)
		(pad "BU1" smd oval
			(at 1.450086 -3.938524)
			(size 0.254 0.3302)
			(layers "F.Cu" "F.Mask" "F.Paste")
			(net "P5E_CPU0_P1_RX_BUF_DP<9>")
		)
		(pad "BU35" smd oval
			(at 1.450086 3.940048)
			(size 0.254 0.3302)
			(layers "F.Cu" "F.Mask" "F.Paste")
			(net "P5E_CPU0_P1_TX_C_DP<9>")
		)
		(pad "BV4" smd circle
			(at 1.20269 -2.817368)
			(size 0.381 0.381)
			(layers "F.Cu" "F.Mask" "F.Paste")
			(net "GND")
		)
		(pad "BV13" smd circle
			(at 1.20269 -0.79629)
			(size 0.3048 0.3048)
			(layers "F.Cu" "F.Mask" "F.Paste")
			(net "GND")
		)
		(pad "BV17" smd circle
			(at 1.20269 -0.296164)
			(size 0.3048 0.3048)
			(layers "F.Cu" "F.Mask" "F.Paste")
			(net "P1V8_CPU0_RT1_1A_1D")
		)
		(pad "BV20" smd circle
			(at 1.20269 0.203708)
			(size 0.3048 0.3048)
			(layers "F.Cu" "F.Mask" "F.Paste")
			(net "P1V8_CPU0_RT1_1A")
		)
		(pad "BV22" smd circle
			(at 1.20269 0.703834)
			(size 0.3048 0.3048)
			(layers "F.Cu" "F.Mask" "F.Paste")
			(net "GND")
		)
	)
)
